# S9S_MB_2U (Grand Teton) — schematic netlist excerpt (pin names and nets, part order shuffled) for the footprints in the layout excerpt that follows; sources: Cadence DE-HDL packaged netlist, KiCad conversion of 03242023_DA0F0TMBIJ0_F0T_Motherboard_J_brd_V01_OCP.brd

R3872  Q_RES  0 5% CHIP  pkg 0402LF  page 157 : A = P12V_OCP_IMON_1 ; B = P12V_OCP_SFF_ISENSE_MPS_TIC
R3517  Q_RES  0 5% CHIP  pkg 0402LF  page 227 : A = GPU_PEX_STRAP1 ; B = GPU_PEX_STRAP1_R
C255  Q_CAP  47UF 4V 20% X6S  pkg C0805  page 77 : A = PVCCIN_CPU1 ; B = GND

(kicad_pcb
	(version 20260206)
	(generator "pcbnew")
	(generator_version "10.0")
	(general
		(thickness 1.6)
		(legacy_teardrops no)
	)
	(paper "A4")
	(title_block
		(title "03242023_DA0F0TMBIJ0_F0T_Motherboard_J_brd_V01_OCP.brd")
		(comment 1 "Grand Teton / footprints 4115-4117 of 6105")
	)
	(layers
		(0 "F.Cu" signal "TOP")
		(4 "In1.Cu" signal "GND")
		(6 "In2.Cu" signal "IN1")
		(8 "In3.Cu" signal "GND1")
		(10 "In4.Cu" signal "IN2")
		(12 "In5.Cu" signal "GND2")
		(14 "In6.Cu" signal "IN3")
		(16 "In7.Cu" signal "GND3")
		(18 "In8.Cu" signal "VCC")
		(20 "In9.Cu" signal "VCC1")
		(22 "In10.Cu" signal "GND4")
		(24 "In11.Cu" signal "IN4")
		(26 "In12.Cu" signal "GND5")
		(28 "In13.Cu" signal "IN5")
		(30 "In14.Cu" signal "GND6")
		(32 "In15.Cu" signal "IN6")
		(34 "In16.Cu" signal "GND7")
		(2 "B.Cu" signal "BOTTOM")
		(9 "F.Adhes" user "F.Adhesive")
		(11 "B.Adhes" user "B.Adhesive")
		(13 "F.Paste" user "Package Geometry/Pastemask Top")
		(15 "B.Paste" user "Package Geometry/Pastemask Bottom")
		(5 "F.SilkS" user "Ref Des/Silkscreen Top")
		(7 "B.SilkS" user "Ref Des/Silkscreen Bottom")
		(1 "F.Mask" user "Board Geometry/Soldermask Top")
		(3 "B.Mask" user "Board Geometry/Soldermask Bottom")
		(17 "Dwgs.User" user "User.Drawings")
		(19 "Cmts.User" user "User.Comments")
		(21 "Eco1.User" user "User.Eco1")
		(23 "Eco2.User" user "User.Eco2")
		(25 "Edge.Cuts" user "Board Geometry/Outline")
		(27 "Margin" user)
		(31 "F.CrtYd" user "Package Geometry/Place Bound Top")
		(29 "B.CrtYd" user "Package Geometry/Place Bound Bottom")
		(35 "F.Fab" user "Ref Des/Assembly Top")
		(33 "B.Fab" user "Ref Des/Assembly Bottom")
	)
	(footprint ""
		(layer "F.Cu")
		(at 436.224172 -32.173418 90)
		(property "Reference" "R3872"
			(at 0 0 90)
			(layer "F.SilkS")
			(hide yes)
			(effects
				(font
					(size 1.27 1.27)
				)
			)
		)
		(property "Value" ""
			(at 0 0 90)
			(layer "F.Fab")
			(effects
				(font
					(size 1.27 1.27)
				)
			)
		)
		(duplicate_pad_numbers_are_jumpers no)
		(fp_line
			(start 0.7874 -0.4064)
			(end 0.7874 0.4064)
			(stroke
				(width 0.1524)
				(type default)
			)
			(layer "F.SilkS")
		)
		(fp_line
			(start -0.7874 -0.4064)
			(end 0.7874 -0.4064)
			(stroke
				(width 0.1524)
				(type default)
			)
			(layer "F.SilkS")
		)
		(fp_line
			(start 0.7874 0.4064)
			(end -0.7874 0.4064)
			(stroke
				(width 0.1524)
				(type default)
			)
			(layer "F.SilkS")
		)
		(fp_line
			(start -0.7874 0.4064)
			(end -0.7874 -0.4064)
			(stroke
				(width 0.1524)
				(type default)
			)
			(layer "F.SilkS")
		)
		(fp_line
			(start -0.12065 -0.305054)
			(end -0.12065 -0.2794)
			(stroke
				(width 0.1)
				(type default)
			)
			(layer "F.Fab")
		)
		(fp_line
			(start -0.67945 -0.305054)
			(end -0.12065 -0.305054)
			(stroke
				(width 0.1)
				(type default)
			)
			(layer "F.Fab")
		)
		(fp_line
			(start 0.67945 -0.3048)
			(end 0.67945 0.3048)
			(stroke
				(width 0.1)
				(type default)
			)
			(layer "F.Fab")
		)
		(fp_line
			(start 0.12065 -0.3048)
			(end 0.67945 -0.3048)
			(stroke
				(width 0.1)
				(type default)
			)
			(layer "F.Fab")
		)
		(fp_line
			(start 0.12065 -0.2794)
			(end 0.12065 -0.3048)
			(stroke
				(width 0.1)
				(type default)
			)
			(layer "F.Fab")
		)
		(fp_line
			(start -0.12065 -0.2794)
			(end 0.12065 -0.2794)
			(stroke
				(width 0.1)
				(type default)
			)
			(layer "F.Fab")
		)
		(fp_line
			(start 0.120396 0.2794)
			(end -0.12065 0.2794)
			(stroke
				(width 0.1)
				(type default)
			)
			(layer "F.Fab")
		)
		(fp_line
			(start -0.12065 0.2794)
			(end -0.12065 0.3048)
			(stroke
				(width 0.1)
				(type default)
			)
			(layer "F.Fab")
		)
		(fp_line
			(start 0.67945 0.3048)
			(end 0.120396 0.3048)
			(stroke
				(width 0.1)
				(type default)
			)
			(layer "F.Fab")
		)
		(fp_line
			(start 0.120396 0.3048)
			(end 0.120396 0.2794)
			(stroke
				(width 0.1)
				(type default)
			)
			(layer "F.Fab")
		)
		(fp_line
			(start -0.12065 0.3048)
			(end -0.67945 0.3048)
			(stroke
				(width 0.1)
				(type default)
			)
			(layer "F.Fab")
		)
		(fp_line
			(start -0.67945 0.3048)
			(end -0.67945 -0.305054)
			(stroke
				(width 0.1)
				(type default)
			)
			(layer "F.Fab")
		)
		(pad "1" smd circle
			(at -0.40005 0 90)
			(size 0 0)
			(layers "F.Cu" "F.Mask" "F.Paste")
			(net "P12V_OCP_IMON_1")
		)
		(pad "2" smd circle
			(at 0.40005 0 90)
			(size 0 0)
			(layers "F.Cu" "F.Mask" "F.Paste")
			(net "P12V_OCP_SFF_ISENSE_MPS_TIC")
		)
	)
	(footprint ""
		(layer "F.Cu")
		(at 105.39222 -294.01008 180)
		(property "Reference" "C255"
			(at 0 0 180)
			(layer "F.SilkS")
			(hide yes)
			(effects
				(font
					(size 1.27 1.27)
				)
			)
		)
		(property "Value" ""
			(at 0 0 180)
			(layer "F.Fab")
			(effects
				(font
					(size 1.27 1.27)
				)
			)
		)
		(duplicate_pad_numbers_are_jumpers no)
		(fp_line
			(start 1.524 0.762)
			(end -1.524 0.762)
			(stroke
				(width 0.1524)
				(type default)
			)
			(layer "F.SilkS")
		)
		(fp_line
			(start 1.524 -0.762)
			(end 1.524 0.762)
			(stroke
				(width 0.1524)
				(type default)
			)
			(layer "F.SilkS")
		)
		(fp_line
			(start -1.524 0.762)
			(end -1.524 -0.762)
			(stroke
				(width 0.1524)
				(type default)
			)
			(layer "F.SilkS")
		)
		(fp_line
			(start -1.524 -0.762)
			(end 1.524 -0.762)
			(stroke
				(width 0.1524)
				(type default)
			)
			(layer "F.SilkS")
		)
		(fp_line
			(start 1.1049 0.724916)
			(end 1.1049 -0.724916)
			(stroke
				(width 0.1)
				(type default)
			)
			(layer "F.Fab")
		)
		(fp_line
			(start 1.1049 -0.724916)
			(end -1.1049 -0.724916)
			(stroke
				(width 0.1)
				(type default)
			)
			(layer "F.Fab")
		)
		(fp_line
			(start -1.1049 0.724916)
			(end 1.1049 0.724916)
			(stroke
				(width 0.1)
				(type default)
			)
			(layer "F.Fab")
		)
		(fp_line
			(start -1.1049 -0.724916)
			(end -1.1049 0.724916)
			(stroke
				(width 0.1)
				(type default)
			)
			(layer "F.Fab")
		)
		(pad "1" smd rect
			(at -0.889 0)
			(size 1.016 1.27)
			(layers "F.Cu" "F.Mask" "F.Paste")
			(net "PVCCIN_CPU1")
		)
		(pad "2" smd rect
			(at 0.889 0)
			(size 1.016 1.27)
			(layers "F.Cu" "F.Mask" "F.Paste")
			(net "GND")
		)
	)
	(footprint ""
		(layer "F.Cu")
		(at 17.737582 -423.629836 -90)
		(property "Reference" "R3517"
			(at 0 0 270)
			(layer "F.SilkS")
			(hide yes)
			(effects
				(font
					(size 1.27 1.27)
				)
			)
		)
		(property "Value" ""
			(at 0 0 270)
			(layer "F.Fab")
			(effects
				(font
					(size 1.27 1.27)
				)
			)
		)
		(duplicate_pad_numbers_are_jumpers no)
		(fp_line
			(start -0.7874 0.4064)
			(end -0.7874 -0.4064)
			(stroke
				(width 0.1524)
				(type default)
			)
			(layer "F.SilkS")
		)
		(fp_line
			(start 0.7874 0.4064)
			(end -0.7874 0.4064)
			(stroke
				(width 0.1524)
				(type default)
			)
			(layer "F.SilkS")
		)
		(fp_line
			(start -0.7874 -0.4064)
			(end 0.7874 -0.4064)
			(stroke
				(width 0.1524)
				(type default)
			)
			(layer "F.SilkS")
		)
		(fp_line
			(start 0.7874 -0.4064)
			(end 0.7874 0.4064)
			(stroke
				(width 0.1524)
				(type default)
			)
			(layer "F.SilkS")
		)
		(fp_line
			(start -0.67945 0.3048)
			(end -0.67945 -0.305054)
			(stroke
				(width 0.1)
				(type default)
			)
			(layer "F.Fab")
		)
		(fp_line
			(start -0.12065 0.3048)
			(end -0.67945 0.3048)
			(stroke
				(width 0.1)
				(type default)
			)
			(layer "F.Fab")
		)
		(fp_line
			(start 0.120396 0.3048)
			(end 0.120396 0.2794)
			(stroke
				(width 0.1)
				(type default)
			)
			(layer "F.Fab")
		)
		(fp_line
			(start 0.67945 0.3048)
			(end 0.120396 0.3048)
			(stroke
				(width 0.1)
				(type default)
			)
			(layer "F.Fab")
		)
		(fp_line
			(start -0.12065 0.2794)
			(end -0.12065 0.3048)
			(stroke
				(width 0.1)
				(type default)
			)
			(layer "F.Fab")
		)
		(fp_line
			(start 0.120396 0.2794)
			(end -0.12065 0.2794)
			(stroke
				(width 0.1)
				(type default)
			)
			(layer "F.Fab")
		)
		(fp_line
			(start -0.12065 -0.2794)
			(end 0.12065 -0.2794)
			(stroke
				(width 0.1)
				(type default)
			)
			(layer "F.Fab")
		)
		(fp_line
			(start 0.12065 -0.2794)
			(end 0.12065 -0.3048)
			(stroke
				(width 0.1)
				(type default)
			)
			(layer "F.Fab")
		)
		(fp_line
			(start 0.12065 -0.3048)
			(end 0.67945 -0.3048)
			(stroke
				(width 0.1)
				(type default)
			)
			(layer "F.Fab")
		)
		(fp_line
			(start 0.67945 -0.3048)
			(end 0.67945 0.3048)
			(stroke
				(width 0.1)
				(type default)
			)
			(layer "F.Fab")
		)
		(fp_line
			(start -0.67945 -0.305054)
			(end -0.12065 -0.305054)
			(stroke
				(width 0.1)
				(type default)
			)
			(layer "F.Fab")
		)
		(fp_line
			(start -0.12065 -0.305054)
			(end -0.12065 -0.2794)
			(stroke
				(width 0.1)
				(type default)
			)
			(layer "F.Fab")
		)
		(pad "1" smd circle
			(at -0.40005 0 270)
			(size 0 0)
			(layers "F.Cu" "F.Mask" "F.Paste")
			(net "GPU_PEX_STRAP1")
		)
		(pad "2" smd circle
			(at 0.40005 0 270)
			(size 0 0)
			(layers "F.Cu" "F.Mask" "F.Paste")
			(net "GPU_PEX_STRAP1_R")
		)
	)
)
